(kicad_pcb
	(version 20260206)
	(generator "pcbnew")
	(generator_version "10.0")
	(general
		(thickness 1.6)
		(legacy_teardrops no)
	)
	(paper "A4")
	(title_block
		(title "01162023_DA0F0TEBIF0_F0T_Expander_BD_F_brd_V02_OCP.brd")
		(comment 1 "Grand Teton / footprints 8212-8219 of 9728")
	)
	(layers
		(0 "F.Cu" signal "TOP")
		(4 "In1.Cu" signal "GND")
		(6 "In2.Cu" signal "VCC")
		(8 "In3.Cu" signal "VCC1")
		(10 "In4.Cu" signal "GND1")
		(12 "In5.Cu" signal "IN1")
		(14 "In6.Cu" signal "GND2")
		(16 "In7.Cu" signal "IN2")
		(18 "In8.Cu" signal "GND3")
		(20 "In9.Cu" signal "IN3")
		(22 "In10.Cu" signal "GND4")
		(24 "In11.Cu" signal "IN4")
		(26 "In12.Cu" signal "GND5")
		(28 "In13.Cu" signal "IN5")
		(30 "In14.Cu" signal "GND6")
		(32 "In15.Cu" signal "IN6")
		(34 "In16.Cu" signal "GND7")
		(2 "B.Cu" signal "BOTTOM")
		(9 "F.Adhes" user "F.Adhesive")
		(11 "B.Adhes" user "B.Adhesive")
		(13 "F.Paste" user "Package Geometry/Pastemask Top")
		(15 "B.Paste" user "Package Geometry/Pastemask Bottom")
		(5 "F.SilkS" user "Ref Des/Silkscreen Top")
		(7 "B.SilkS" user "Ref Des/Silkscreen Bottom")
		(1 "F.Mask" user "Board Geometry/Soldermask Top")
		(3 "B.Mask" user "Board Geometry/Soldermask Bottom")
		(17 "Dwgs.User" user "User.Drawings")
		(19 "Cmts.User" user "User.Comments")
		(21 "Eco1.User" user "User.Eco1")
		(23 "Eco2.User" user "User.Eco2")
		(25 "Edge.Cuts" user "Board Geometry/Outline")
		(27 "Margin" user)
		(31 "F.CrtYd" user "Package Geometry/Place Bound Top")
		(29 "B.CrtYd" user "Package Geometry/Place Bound Bottom")
		(35 "F.Fab" user "Ref Des/Assembly Top")
		(33 "B.Fab" user "Ref Des/Assembly Bottom")
	)
	(footprint ""
		(layer "B.Cu")
		(at 124.331222 -200.92035)
		(property "Reference" "R923"
			(at 0 0 0)
			(layer "B.SilkS")
			(hide yes)
			(effects
				(font
					(size 1.27 1.27)
				)
				(justify mirror)
			)
		)
		(property "Value" ""
			(at 0 0 0)
			(layer "B.Fab")
			(effects
				(font
					(size 1.27 1.27)
				)
				(justify mirror)
			)
		)
		(duplicate_pad_numbers_are_jumpers no)
		(fp_line
			(start -0.7874 -0.4064)
			(end -0.7874 0.4064)
			(stroke
				(width 0.1524)
				(type default)
			)
			(layer "B.SilkS")
		)
		(fp_line
			(start -0.7874 0.4064)
			(end 0.7874 0.4064)
			(stroke
				(width 0.1524)
				(type default)
			)
			(layer "B.SilkS")
		)
		(fp_line
			(start 0.7874 -0.4064)
			(end -0.7874 -0.4064)
			(stroke
				(width 0.1524)
				(type default)
			)
			(layer "B.SilkS")
		)
		(fp_line
			(start 0.7874 0.4064)
			(end 0.7874 -0.4064)
			(stroke
				(width 0.1524)
				(type default)
			)
			(layer "B.SilkS")
		)
		(fp_line
			(start -0.67945 -0.3048)
			(end -0.67945 0.3048)
			(stroke
				(width 0.1)
				(type default)
			)
			(layer "B.Fab")
		)
		(fp_line
			(start -0.67945 0.3048)
			(end -0.120396 0.3048)
			(stroke
				(width 0.1)
				(type default)
			)
			(layer "B.Fab")
		)
		(fp_line
			(start -0.12065 -0.3048)
			(end -0.67945 -0.3048)
			(stroke
				(width 0.1)
				(type default)
			)
			(layer "B.Fab")
		)
		(fp_line
			(start -0.12065 -0.2794)
			(end -0.12065 -0.3048)
			(stroke
				(width 0.1)
				(type default)
			)
			(layer "B.Fab")
		)
		(fp_line
			(start -0.120396 0.2794)
			(end 0.12065 0.2794)
			(stroke
				(width 0.1)
				(type default)
			)
			(layer "B.Fab")
		)
		(fp_line
			(start -0.120396 0.3048)
			(end -0.120396 0.2794)
			(stroke
				(width 0.1)
				(type default)
			)
			(layer "B.Fab")
		)
		(fp_line
			(start 0.12065 -0.305054)
			(end 0.12065 -0.2794)
			(stroke
				(width 0.1)
				(type default)
			)
			(layer "B.Fab")
		)
		(fp_line
			(start 0.12065 -0.2794)
			(end -0.12065 -0.2794)
			(stroke
				(width 0.1)
				(type default)
			)
			(layer "B.Fab")
		)
		(fp_line
			(start 0.12065 0.2794)
			(end 0.12065 0.3048)
			(stroke
				(width 0.1)
				(type default)
			)
			(layer "B.Fab")
		)
		(fp_line
			(start 0.12065 0.3048)
			(end 0.67945 0.3048)
			(stroke
				(width 0.1)
				(type default)
			)
			(layer "B.Fab")
		)
		(fp_line
			(start 0.67945 -0.305054)
			(end 0.12065 -0.305054)
			(stroke
				(width 0.1)
				(type default)
			)
			(layer "B.Fab")
		)
		(fp_line
			(start 0.67945 0.3048)
			(end 0.67945 -0.305054)
			(stroke
				(width 0.1)
				(type default)
			)
			(layer "B.Fab")
		)
		(pad "1" smd circle
			(at 0.40005 0 180)
			(size 0 0)
			(layers "B.Cu" "B.Mask" "B.Paste")
			(net "FT4232_CLI_EEPROM_R_SDA")
		)
		(pad "2" smd circle
			(at -0.40005 0 180)
			(size 0 0)
			(layers "B.Cu" "B.Mask" "B.Paste")
			(net "FT4232_CLI_EEPROM_DO")
		)
	)
	(footprint ""
		(layer "B.Cu")
		(at 56.799988 -292.099746 90)
		(property "Reference" "C1197"
			(at 0 0 90)
			(layer "B.SilkS")
			(hide yes)
			(effects
				(font
					(size 1.27 1.27)
				)
				(justify mirror)
			)
		)
		(property "Value" ""
			(at 0 0 90)
			(layer "B.Fab")
			(effects
				(font
					(size 1.27 1.27)
				)
				(justify mirror)
			)
		)
		(duplicate_pad_numbers_are_jumpers no)
		(fp_line
			(start 0.299974 -0.150114)
			(end -0.299974 -0.150114)
			(stroke
				(width 0.1)
				(type default)
			)
			(layer "B.Fab")
		)
		(fp_line
			(start -0.299974 -0.150114)
			(end -0.299974 0.150114)
			(stroke
				(width 0.1)
				(type default)
			)
			(layer "B.Fab")
		)
		(fp_line
			(start 0.299974 0.150114)
			(end 0.299974 -0.150114)
			(stroke
				(width 0.1)
				(type default)
			)
			(layer "B.Fab")
		)
		(fp_line
			(start -0.299974 0.150114)
			(end 0.299974 0.150114)
			(stroke
				(width 0.1)
				(type default)
			)
			(layer "B.Fab")
		)
		(pad "1" smd rect
			(at 0.2667 0 270)
			(size 0.3048 0.381)
			(layers "B.Cu" "B.Mask" "B.Paste")
			(net "P0V8_SERDES_VDDA_PEX0")
		)
		(pad "2" smd rect
			(at -0.2667 0 270)
			(size 0.3048 0.381)
			(layers "B.Cu" "B.Mask" "B.Paste")
			(net "GND")
		)
	)
	(footprint ""
		(layer "B.Cu")
		(at 295.583356 -108.462318 180)
		(property "Reference" "R285"
			(at 0 0 0)
			(layer "B.SilkS")
			(hide yes)
			(effects
				(font
					(size 1.27 1.27)
				)
				(justify mirror)
			)
		)
		(property "Value" ""
			(at 0 0 0)
			(layer "B.Fab")
			(effects
				(font
					(size 1.27 1.27)
				)
				(justify mirror)
			)
		)
		(duplicate_pad_numbers_are_jumpers no)
		(fp_line
			(start 0.7874 0.4064)
			(end 0.7874 -0.4064)
			(stroke
				(width 0.1524)
				(type default)
			)
			(layer "B.SilkS")
		)
		(fp_line
			(start 0.7874 -0.4064)
			(end -0.7874 -0.4064)
			(stroke
				(width 0.1524)
				(type default)
			)
			(layer "B.SilkS")
		)
		(fp_line
			(start -0.7874 0.4064)
			(end 0.7874 0.4064)
			(stroke
				(width 0.1524)
				(type default)
			)
			(layer "B.SilkS")
		)
		(fp_line
			(start -0.7874 -0.4064)
			(end -0.7874 0.4064)
			(stroke
				(width 0.1524)
				(type default)
			)
			(layer "B.SilkS")
		)
		(fp_line
			(start 0.67945 0.3048)
			(end 0.67945 -0.305054)
			(stroke
				(width 0.1)
				(type default)
			)
			(layer "B.Fab")
		)
		(fp_line
			(start 0.67945 -0.305054)
			(end 0.12065 -0.305054)
			(stroke
				(width 0.1)
				(type default)
			)
			(layer "B.Fab")
		)
		(fp_line
			(start 0.12065 0.3048)
			(end 0.67945 0.3048)
			(stroke
				(width 0.1)
				(type default)
			)
			(layer "B.Fab")
		)
		(fp_line
			(start 0.12065 0.2794)
			(end 0.12065 0.3048)
			(stroke
				(width 0.1)
				(type default)
			)
			(layer "B.Fab")
		)
		(fp_line
			(start 0.12065 -0.2794)
			(end -0.12065 -0.2794)
			(stroke
				(width 0.1)
				(type default)
			)
			(layer "B.Fab")
		)
		(fp_line
			(start 0.12065 -0.305054)
			(end 0.12065 -0.2794)
			(stroke
				(width 0.1)
				(type default)
			)
			(layer "B.Fab")
		)
		(fp_line
			(start -0.120396 0.3048)
			(end -0.120396 0.2794)
			(stroke
				(width 0.1)
				(type default)
			)
			(layer "B.Fab")
		)
		(fp_line
			(start -0.120396 0.2794)
			(end 0.12065 0.2794)
			(stroke
				(width 0.1)
				(type default)
			)
			(layer "B.Fab")
		)
		(fp_line
			(start -0.12065 -0.2794)
			(end -0.12065 -0.3048)
			(stroke
				(width 0.1)
				(type default)
			)
			(layer "B.Fab")
		)
		(fp_line
			(start -0.12065 -0.3048)
			(end -0.67945 -0.3048)
			(stroke
				(width 0.1)
				(type default)
			)
			(layer "B.Fab")
		)
		(fp_line
			(start -0.67945 0.3048)
			(end -0.120396 0.3048)
			(stroke
				(width 0.1)
				(type default)
			)
			(layer "B.Fab")
		)
		(fp_line
			(start -0.67945 -0.3048)
			(end -0.67945 0.3048)
			(stroke
				(width 0.1)
				(type default)
			)
			(layer "B.Fab")
		)
		(pad "1" smd circle
			(at 0.40005 0)
			(size 0 0)
			(layers "B.Cu" "B.Mask" "B.Paste")
			(net "NIC5_BIF0_N")
		)
		(pad "2" smd circle
			(at -0.40005 0)
			(size 0 0)
			(layers "B.Cu" "B.Mask" "B.Paste")
			(net "GND")
		)
	)
	(footprint ""
		(layer "B.Cu")
		(at 357.620316 -285.613348 -90)
		(property "Reference" "PR7181"
			(at 0 0 90)
			(layer "B.SilkS")
			(hide yes)
			(effects
				(font
					(size 1.27 1.27)
				)
				(justify mirror)
			)
		)
		(property "Value" ""
			(at 0 0 90)
			(layer "B.Fab")
			(effects
				(font
					(size 1.27 1.27)
				)
				(justify mirror)
			)
		)
		(duplicate_pad_numbers_are_jumpers no)
		(fp_line
			(start -0.7874 0.4064)
			(end 0.7874 0.4064)
			(stroke
				(width 0.1524)
				(type default)
			)
			(layer "B.SilkS")
		)
		(fp_line
			(start 0.7874 0.4064)
			(end 0.7874 -0.4064)
			(stroke
				(width 0.1524)
				(type default)
			)
			(layer "B.SilkS")
		)
		(fp_line
			(start -0.7874 -0.4064)
			(end -0.7874 0.4064)
			(stroke
				(width 0.1524)
				(type default)
			)
			(layer "B.SilkS")
		)
		(fp_line
			(start 0.7874 -0.4064)
			(end -0.7874 -0.4064)
			(stroke
				(width 0.1524)
				(type default)
			)
			(layer "B.SilkS")
		)
		(fp_line
			(start -0.67945 0.3048)
			(end -0.120396 0.3048)
			(stroke
				(width 0.1)
				(type default)
			)
			(layer "B.Fab")
		)
		(fp_line
			(start -0.120396 0.3048)
			(end -0.120396 0.2794)
			(stroke
				(width 0.1)
				(type default)
			)
			(layer "B.Fab")
		)
		(fp_line
			(start 0.12065 0.3048)
			(end 0.67945 0.3048)
			(stroke
				(width 0.1)
				(type default)
			)
			(layer "B.Fab")
		)
		(fp_line
			(start 0.67945 0.3048)
			(end 0.67945 -0.305054)
			(stroke
				(width 0.1)
				(type default)
			)
			(layer "B.Fab")
		)
		(fp_line
			(start -0.120396 0.2794)
			(end 0.12065 0.2794)
			(stroke
				(width 0.1)
				(type default)
			)
			(layer "B.Fab")
		)
		(fp_line
			(start 0.12065 0.2794)
			(end 0.12065 0.3048)
			(stroke
				(width 0.1)
				(type default)
			)
			(layer "B.Fab")
		)
		(fp_line
			(start -0.12065 -0.2794)
			(end -0.12065 -0.3048)
			(stroke
				(width 0.1)
				(type default)
			)
			(layer "B.Fab")
		)
		(fp_line
			(start 0.12065 -0.2794)
			(end -0.12065 -0.2794)
			(stroke
				(width 0.1)
				(type default)
			)
			(layer "B.Fab")
		)
		(fp_line
			(start -0.67945 -0.3048)
			(end -0.67945 0.3048)
			(stroke
				(width 0.1)
				(type default)
			)
			(layer "B.Fab")
		)
		(fp_line
			(start -0.12065 -0.3048)
			(end -0.67945 -0.3048)
			(stroke
				(width 0.1)
				(type default)
			)
			(layer "B.Fab")
		)
		(fp_line
			(start 0.12065 -0.305054)
			(end 0.12065 -0.2794)
			(stroke
				(width 0.1)
				(type default)
			)
			(layer "B.Fab")
		)
		(fp_line
			(start 0.67945 -0.305054)
			(end 0.12065 -0.305054)
			(stroke
				(width 0.1)
				(type default)
			)
			(layer "B.Fab")
		)
		(pad "1" smd circle
			(at 0.40005 0 90)
			(size 0 0)
			(layers "B.Cu" "B.Mask" "B.Paste")
			(net "P0V8_PEX3_PVCC")
		)
		(pad "2" smd circle
			(at -0.40005 0 90)
			(size 0 0)
			(layers "B.Cu" "B.Mask" "B.Paste")
			(net "P3V3_AUX")
		)
	)
	(footprint ""
		(layer "B.Cu")
		(at 406.999948 -301.599854 -90)
		(property "Reference" "C1951"
			(at 0 0 90)
			(layer "B.SilkS")
			(hide yes)
			(effects
				(font
					(size 1.27 1.27)
				)
				(justify mirror)
			)
		)
		(property "Value" ""
			(at 0 0 90)
			(layer "B.Fab")
			(effects
				(font
					(size 1.27 1.27)
				)
				(justify mirror)
			)
		)
		(duplicate_pad_numbers_are_jumpers no)
		(fp_line
			(start -0.299974 0.150114)
			(end 0.299974 0.150114)
			(stroke
				(width 0.1)
				(type default)
			)
			(layer "B.Fab")
		)
		(fp_line
			(start 0.299974 0.150114)
			(end 0.299974 -0.150114)
			(stroke
				(width 0.1)
				(type default)
			)
			(layer "B.Fab")
		)
		(fp_line
			(start -0.299974 -0.150114)
			(end -0.299974 0.150114)
			(stroke
				(width 0.1)
				(type default)
			)
			(layer "B.Fab")
		)
		(fp_line
			(start 0.299974 -0.150114)
			(end -0.299974 -0.150114)
			(stroke
				(width 0.1)
				(type default)
			)
			(layer "B.Fab")
		)
		(pad "1" smd rect
			(at 0.2667 0 90)
			(size 0.3048 0.381)
			(layers "B.Cu" "B.Mask" "B.Paste")
			(net "P0V8_SERDES_VDDA_PEX3")
		)
		(pad "2" smd rect
			(at -0.2667 0 90)
			(size 0.3048 0.381)
			(layers "B.Cu" "B.Mask" "B.Paste")
			(net "GND")
		)
	)
	(footprint ""
		(layer "B.Cu")
		(at 163.874958 -295.4528 90)
		(property "Reference" "C3214"
			(at 0 0 90)
			(layer "B.SilkS")
			(hide yes)
			(effects
				(font
					(size 1.27 1.27)
				)
				(justify mirror)
			)
		)
		(property "Value" ""
			(at 0 0 90)
			(layer "B.Fab")
			(effects
				(font
					(size 1.27 1.27)
				)
				(justify mirror)
			)
		)
		(duplicate_pad_numbers_are_jumpers no)
		(fp_line
			(start 0.299974 -0.150114)
			(end -0.299974 -0.150114)
			(stroke
				(width 0.1)
				(type default)
			)
			(layer "B.Fab")
		)
		(fp_line
			(start -0.299974 -0.150114)
			(end -0.299974 0.150114)
			(stroke
				(width 0.1)
				(type default)
			)
			(layer "B.Fab")
		)
		(fp_line
			(start 0.299974 0.150114)
			(end 0.299974 -0.150114)
			(stroke
				(width 0.1)
				(type default)
			)
			(layer "B.Fab")
		)
		(fp_line
			(start -0.299974 0.150114)
			(end 0.299974 0.150114)
			(stroke
				(width 0.1)
				(type default)
			)
			(layer "B.Fab")
		)
		(pad "1" smd rect
			(at 0.2667 0 270)
			(size 0.3048 0.381)
			(layers "B.Cu" "B.Mask" "B.Paste")
			(net "PCEPLL3_VDDA18_PEX1")
		)
		(pad "2" smd rect
			(at -0.2667 0 270)
			(size 0.3048 0.381)
			(layers "B.Cu" "B.Mask" "B.Paste")
			(net "GND")
		)
	)
	(footprint ""
		(layer "B.Cu")
		(at 109.142022 -88.822784 180)
		(property "Reference" "C2665"
			(at 0 0 0)
			(layer "B.SilkS")
			(hide yes)
			(effects
				(font
					(size 1.27 1.27)
				)
				(justify mirror)
			)
		)
		(property "Value" ""
			(at 0 0 0)
			(layer "B.Fab")
			(effects
				(font
					(size 1.27 1.27)
				)
				(justify mirror)
			)
		)
		(duplicate_pad_numbers_are_jumpers no)
		(fp_line
			(start 0.7874 0.4064)
			(end 0.7874 -0.4064)
			(stroke
				(width 0.1524)
				(type default)
			)
			(layer "B.SilkS")
		)
		(fp_line
			(start 0.7874 -0.4064)
			(end -0.7874 -0.4064)
			(stroke
				(width 0.1524)
				(type default)
			)
			(layer "B.SilkS")
		)
		(fp_line
			(start -0.7874 0.4064)
			(end 0.7874 0.4064)
			(stroke
				(width 0.1524)
				(type default)
			)
			(layer "B.SilkS")
		)
		(fp_line
			(start -0.7874 -0.4064)
			(end -0.7874 0.4064)
			(stroke
				(width 0.1524)
				(type default)
			)
			(layer "B.SilkS")
		)
		(fp_line
			(start 0.67945 0.3048)
			(end 0.67945 -0.305054)
			(stroke
				(width 0.1)
				(type default)
			)
			(layer "B.Fab")
		)
		(fp_line
			(start 0.67945 -0.305054)
			(end 0.12065 -0.305054)
			(stroke
				(width 0.1)
				(type default)
			)
			(layer "B.Fab")
		)
		(fp_line
			(start 0.12065 0.3048)
			(end 0.67945 0.3048)
			(stroke
				(width 0.1)
				(type default)
			)
			(layer "B.Fab")
		)
		(fp_line
			(start 0.12065 0.2794)
			(end 0.12065 0.3048)
			(stroke
				(width 0.1)
				(type default)
			)
			(layer "B.Fab")
		)
		(fp_line
			(start 0.12065 -0.2794)
			(end -0.12065 -0.2794)
			(stroke
				(width 0.1)
				(type default)
			)
			(layer "B.Fab")
		)
		(fp_line
			(start 0.12065 -0.305054)
			(end 0.12065 -0.2794)
			(stroke
				(width 0.1)
				(type default)
			)
			(layer "B.Fab")
		)
		(fp_line
			(start -0.120396 0.3048)
			(end -0.120396 0.2794)
			(stroke
				(width 0.1)
				(type default)
			)
			(layer "B.Fab")
		)
		(fp_line
			(start -0.120396 0.2794)
			(end 0.12065 0.2794)
			(stroke
				(width 0.1)
				(type default)
			)
			(layer "B.Fab")
		)
		(fp_line
			(start -0.12065 -0.2794)
			(end -0.12065 -0.3048)
			(stroke
				(width 0.1)
				(type default)
			)
			(layer "B.Fab")
		)
		(fp_line
			(start -0.12065 -0.3048)
			(end -0.67945 -0.3048)
			(stroke
				(width 0.1)
				(type default)
			)
			(layer "B.Fab")
		)
		(fp_line
			(start -0.67945 0.3048)
			(end -0.120396 0.3048)
			(stroke
				(width 0.1)
				(type default)
			)
			(layer "B.Fab")
		)
		(fp_line
			(start -0.67945 -0.3048)
			(end -0.67945 0.3048)
			(stroke
				(width 0.1)
				(type default)
			)
			(layer "B.Fab")
		)
		(pad "1" smd circle
			(at 0.40005 0)
			(size 0 0)
			(layers "B.Cu" "B.Mask" "B.Paste")
			(net "P3V3_VDD_9ZXL0851_0_7")
		)
		(pad "2" smd circle
			(at -0.40005 0)
			(size 0 0)
			(layers "B.Cu" "B.Mask" "B.Paste")
			(net "GND")
		)
	)
	(footprint ""
		(layer "B.Cu")
		(at 256.351532 -83.18754 180)
		(property "Reference" "C2641"
			(at 0 0 0)
			(layer "B.SilkS")
			(hide yes)
			(effects
				(font
					(size 1.27 1.27)
				)
				(justify mirror)
			)
		)
		(property "Value" ""
			(at 0 0 0)
			(layer "B.Fab")
			(effects
				(font
					(size 1.27 1.27)
				)
				(justify mirror)
			)
		)
		(duplicate_pad_numbers_are_jumpers no)
		(fp_line
			(start 0.7874 0.4064)
			(end 0.7874 -0.4064)
			(stroke
				(width 0.1524)
				(type default)
			)
			(layer "B.SilkS")
		)
		(fp_line
			(start 0.7874 -0.4064)
			(end -0.7874 -0.4064)
			(stroke
				(width 0.1524)
				(type default)
			)
			(layer "B.SilkS")
		)
		(fp_line
			(start -0.7874 0.4064)
			(end 0.7874 0.4064)
			(stroke
				(width 0.1524)
				(type default)
			)
			(layer "B.SilkS")
		)
		(fp_line
			(start -0.7874 -0.4064)
			(end -0.7874 0.4064)
			(stroke
				(width 0.1524)
				(type default)
			)
			(layer "B.SilkS")
		)
		(fp_line
			(start 0.67945 0.3048)
			(end 0.67945 -0.305054)
			(stroke
				(width 0.1)
				(type default)
			)
			(layer "B.Fab")
		)
		(fp_line
			(start 0.67945 -0.305054)
			(end 0.12065 -0.305054)
			(stroke
				(width 0.1)
				(type default)
			)
			(layer "B.Fab")
		)
		(fp_line
			(start 0.12065 0.3048)
			(end 0.67945 0.3048)
			(stroke
				(width 0.1)
				(type default)
			)
			(layer "B.Fab")
		)
		(fp_line
			(start 0.12065 0.2794)
			(end 0.12065 0.3048)
			(stroke
				(width 0.1)
				(type default)
			)
			(layer "B.Fab")
		)
		(fp_line
			(start 0.12065 -0.2794)
			(end -0.12065 -0.2794)
			(stroke
				(width 0.1)
				(type default)
			)
			(layer "B.Fab")
		)
		(fp_line
			(start 0.12065 -0.305054)
			(end 0.12065 -0.2794)
			(stroke
				(width 0.1)
				(type default)
			)
			(layer "B.Fab")
		)
		(fp_line
			(start -0.120396 0.3048)
			(end -0.120396 0.2794)
			(stroke
				(width 0.1)
				(type default)
			)
			(layer "B.Fab")
		)
		(fp_line
			(start -0.120396 0.2794)
			(end 0.12065 0.2794)
			(stroke
				(width 0.1)
				(type default)
			)
			(layer "B.Fab")
		)
		(fp_line
			(start -0.12065 -0.2794)
			(end -0.12065 -0.3048)
			(stroke
				(width 0.1)
				(type default)
			)
			(layer "B.Fab")
		)
		(fp_line
			(start -0.12065 -0.3048)
			(end -0.67945 -0.3048)
			(stroke
				(width 0.1)
				(type default)
			)
			(layer "B.Fab")
		)
		(fp_line
			(start -0.67945 0.3048)
			(end -0.120396 0.3048)
			(stroke
				(width 0.1)
				(type default)
			)
			(layer "B.Fab")
		)
		(fp_line
			(start -0.67945 -0.3048)
			(end -0.67945 0.3048)
			(stroke
				(width 0.1)
				(type default)
			)
			(layer "B.Fab")
		)
		(pad "1" smd circle
			(at 0.40005 0)
			(size 0 0)
			(layers "B.Cu" "B.Mask" "B.Paste")
			(net "P3V3_CLK_GEN_VDDXTAL_CK440")
		)
		(pad "2" smd circle
			(at -0.40005 0)
			(size 0 0)
			(layers "B.Cu" "B.Mask" "B.Paste")
			(net "GND")
		)
	)
)
